(kicad_pcb
	(version 20260206)
	(generator "pcbnew")
	(generator_version "10.0")
	(general
		(thickness 1.6)
		(legacy_teardrops no)
	)
	(paper "A4")
	(title_block
		(title "03242023_DA0F0TMBIJ0_F0T_Motherboard_J_brd_V01_OCP.brd")
		(comment 1 "Grand Teton / footprints 3587-3593 of 6105")
	)
	(layers
		(0 "F.Cu" signal "TOP")
		(4 "In1.Cu" signal "GND")
		(6 "In2.Cu" signal "IN1")
		(8 "In3.Cu" signal "GND1")
		(10 "In4.Cu" signal "IN2")
		(12 "In5.Cu" signal "GND2")
		(14 "In6.Cu" signal "IN3")
		(16 "In7.Cu" signal "GND3")
		(18 "In8.Cu" signal "VCC")
		(20 "In9.Cu" signal "VCC1")
		(22 "In10.Cu" signal "GND4")
		(24 "In11.Cu" signal "IN4")
		(26 "In12.Cu" signal "GND5")
		(28 "In13.Cu" signal "IN5")
		(30 "In14.Cu" signal "GND6")
		(32 "In15.Cu" signal "IN6")
		(34 "In16.Cu" signal "GND7")
		(2 "B.Cu" signal "BOTTOM")
		(9 "F.Adhes" user "F.Adhesive")
		(11 "B.Adhes" user "B.Adhesive")
		(13 "F.Paste" user "Package Geometry/Pastemask Top")
		(15 "B.Paste" user "Package Geometry/Pastemask Bottom")
		(5 "F.SilkS" user "Ref Des/Silkscreen Top")
		(7 "B.SilkS" user "Ref Des/Silkscreen Bottom")
		(1 "F.Mask" user "Board Geometry/Soldermask Top")
		(3 "B.Mask" user "Board Geometry/Soldermask Bottom")
		(17 "Dwgs.User" user "User.Drawings")
		(19 "Cmts.User" user "User.Comments")
		(21 "Eco1.User" user "User.Eco1")
		(23 "Eco2.User" user "User.Eco2")
		(25 "Edge.Cuts" user "Board Geometry/Outline")
		(27 "Margin" user)
		(31 "F.CrtYd" user "Package Geometry/Place Bound Top")
		(29 "B.CrtYd" user "Package Geometry/Place Bound Bottom")
		(35 "F.Fab" user "Ref Des/Assembly Top")
		(33 "B.Fab" user "Ref Des/Assembly Bottom")
	)
	(footprint ""
		(layer "F.Cu")
		(at 44.668694 -16.099536 90)
		(property "Reference" "C826"
			(at 0 0 90)
			(layer "F.SilkS")
			(hide yes)
			(effects
				(font
					(size 1.27 1.27)
				)
			)
		)
		(property "Value" ""
			(at 0 0 90)
			(layer "F.Fab")
			(effects
				(font
					(size 1.27 1.27)
				)
			)
		)
		(duplicate_pad_numbers_are_jumpers no)
		(fp_line
			(start 0.299974 -0.150114)
			(end 0.299974 0.150114)
			(stroke
				(width 0.1)
				(type default)
			)
			(layer "F.Fab")
		)
		(fp_line
			(start -0.299974 -0.150114)
			(end 0.299974 -0.150114)
			(stroke
				(width 0.1)
				(type default)
			)
			(layer "F.Fab")
		)
		(fp_line
			(start 0.299974 0.150114)
			(end -0.299974 0.150114)
			(stroke
				(width 0.1)
				(type default)
			)
			(layer "F.Fab")
		)
		(fp_line
			(start -0.299974 0.150114)
			(end -0.299974 -0.150114)
			(stroke
				(width 0.1)
				(type default)
			)
			(layer "F.Fab")
		)
		(pad "1" smd rect
			(at -0.2667 0 90)
			(size 0.3048 0.381)
			(layers "F.Cu" "F.Mask" "F.Paste")
			(net "P5E_CPU1_PE1_TX_C_DN<5>")
		)
		(pad "2" smd rect
			(at 0.2667 0 90)
			(size 0.3048 0.381)
			(layers "F.Cu" "F.Mask" "F.Paste")
			(net "P5E_CPU1_PE1_TX_DN<5>")
		)
	)
	(footprint ""
		(layer "F.Cu")
		(at 457.687426 -103.646224)
		(property "Reference" "U212"
			(at -1.490726 -1.641094 0)
			(unlocked yes)
			(layer "F.SilkS")
			(effects
				(font
					(size 0.7874 0.5842)
					(thickness 0.1524)
				)
				(justify left)
			)
		)
		(property "Value" ""
			(at 0 0 0)
			(layer "F.Fab")
			(effects
				(font
					(size 1.27 1.27)
				)
			)
		)
		(duplicate_pad_numbers_are_jumpers no)
		(fp_line
			(start -1.38176 -1.100074)
			(end -1.38176 1.100074)
			(stroke
				(width 0.1524)
				(type default)
			)
			(layer "F.SilkS")
		)
		(fp_line
			(start -1.38176 1.100074)
			(end 1.38176 1.100074)
			(stroke
				(width 0.1524)
				(type default)
			)
			(layer "F.SilkS")
		)
		(fp_line
			(start -0.592074 -1.100074)
			(end -1.38176 -1.100074)
			(stroke
				(width 0.1524)
				(type default)
			)
			(layer "F.SilkS")
		)
		(fp_line
			(start 0 -0.508)
			(end -0.592074 -1.100074)
			(stroke
				(width 0.1524)
				(type default)
			)
			(layer "F.SilkS")
		)
		(fp_line
			(start 0.592074 -1.100074)
			(end 0 -0.508)
			(stroke
				(width 0.1524)
				(type default)
			)
			(layer "F.SilkS")
		)
		(fp_line
			(start 1.38176 -1.100074)
			(end 0.592074 -1.100074)
			(stroke
				(width 0.1524)
				(type default)
			)
			(layer "F.SilkS")
		)
		(fp_line
			(start 1.38176 1.100074)
			(end 1.38176 -1.100074)
			(stroke
				(width 0.1524)
				(type default)
			)
			(layer "F.SilkS")
		)
		(fp_poly
			(pts
				(xy -1.50241 -0.649986) (xy -1.9431 -0.429768) (xy -1.9431 -0.870204)
			)
			(stroke
				(width 0)
				(type default)
			)
			(fill yes)
			(layer "F.SilkS")
		)
		(fp_line
			(start -0.674878 -1.100074)
			(end -0.674878 1.100074)
			(stroke
				(width 0.1)
				(type default)
			)
			(layer "F.Fab")
		)
		(fp_line
			(start -0.674878 1.100074)
			(end 0.674878 1.100074)
			(stroke
				(width 0.1)
				(type default)
			)
			(layer "F.Fab")
		)
		(fp_line
			(start 0.674878 -1.100074)
			(end -0.674878 -1.100074)
			(stroke
				(width 0.1)
				(type default)
			)
			(layer "F.Fab")
		)
		(fp_line
			(start 0.674878 1.100074)
			(end 0.674878 -1.100074)
			(stroke
				(width 0.1)
				(type default)
			)
			(layer "F.Fab")
		)
		(fp_poly
			(pts
				(xy -1.9431 -0.870204) (xy -1.50241 -0.649986) (xy -1.9431 -0.429768)
			)
			(stroke
				(width 0)
				(type default)
			)
			(fill yes)
			(layer "F.Fab")
		)
		(pad "1" smd rect
			(at -0.94996 -0.649986 270)
			(size 0.4318 0.6096)
			(layers "F.Cu" "F.Mask" "F.Paste")
			(net "OCP_SFF_PRSNT2_R_N")
		)
		(pad "2" smd rect
			(at -0.94996 0 270)
			(size 0.4318 0.6096)
			(layers "F.Cu" "F.Mask" "F.Paste")
			(net "GND")
		)
		(pad "3" smd rect
			(at -0.94996 0.649986 270)
			(size 0.4318 0.6096)
			(layers "F.Cu" "F.Mask" "F.Paste")
			(net "OCP_SFF_PRSNT3_R_N")
		)
		(pad "4" smd rect
			(at 0.94996 0.649986 270)
			(size 0.4318 0.6096)
			(layers "F.Cu" "F.Mask" "F.Paste")
			(net "HP_LVC3_OCP_V3_1_PRSNT2_N_R")
		)
		(pad "5" smd rect
			(at 0.94996 0 270)
			(size 0.4318 0.6096)
			(layers "F.Cu" "F.Mask" "F.Paste")
			(net "P3V3_AUX")
		)
		(pad "6" smd rect
			(at 0.94996 -0.649986 270)
			(size 0.4318 0.6096)
			(layers "F.Cu" "F.Mask" "F.Paste")
			(net "HP_LVC3_OCP_V3_1_PRSNT2_N_R")
		)
	)
	(footprint ""
		(layer "F.Cu")
		(at 24.67356 -76.266548)
		(property "Reference" "U58"
			(at -1.1938 -2.02057 0)
			(unlocked yes)
			(layer "F.SilkS")
			(effects
				(font
					(size 0.7874 0.5842)
					(thickness 0.1524)
				)
				(justify left)
			)
		)
		(property "Value" ""
			(at 0 0 0)
			(layer "F.Fab")
			(effects
				(font
					(size 1.27 1.27)
				)
			)
		)
		(duplicate_pad_numbers_are_jumpers no)
		(fp_line
			(start -1.38176 -1.100074)
			(end -1.38176 1.100074)
			(stroke
				(width 0.1524)
				(type default)
			)
			(layer "F.SilkS")
		)
		(fp_line
			(start -1.38176 1.100074)
			(end 1.38176 1.100074)
			(stroke
				(width 0.1524)
				(type default)
			)
			(layer "F.SilkS")
		)
		(fp_line
			(start -0.592074 -1.100074)
			(end -1.38176 -1.100074)
			(stroke
				(width 0.1524)
				(type default)
			)
			(layer "F.SilkS")
		)
		(fp_line
			(start 0 -0.508)
			(end -0.592074 -1.100074)
			(stroke
				(width 0.1524)
				(type default)
			)
			(layer "F.SilkS")
		)
		(fp_line
			(start 0.592074 -1.100074)
			(end 0 -0.508)
			(stroke
				(width 0.1524)
				(type default)
			)
			(layer "F.SilkS")
		)
		(fp_line
			(start 1.38176 -1.100074)
			(end 0.592074 -1.100074)
			(stroke
				(width 0.1524)
				(type default)
			)
			(layer "F.SilkS")
		)
		(fp_line
			(start 1.38176 1.100074)
			(end 1.38176 -1.100074)
			(stroke
				(width 0.1524)
				(type default)
			)
			(layer "F.SilkS")
		)
		(fp_poly
			(pts
				(xy -1.50241 -0.649986) (xy -1.9431 -0.429768) (xy -1.9431 -0.870204)
			)
			(stroke
				(width 0)
				(type default)
			)
			(fill yes)
			(layer "F.SilkS")
		)
		(fp_line
			(start -0.674878 -1.100074)
			(end -0.674878 1.100074)
			(stroke
				(width 0.1)
				(type default)
			)
			(layer "F.Fab")
		)
		(fp_line
			(start -0.674878 1.100074)
			(end 0.674878 1.100074)
			(stroke
				(width 0.1)
				(type default)
			)
			(layer "F.Fab")
		)
		(fp_line
			(start 0.674878 -1.100074)
			(end -0.674878 -1.100074)
			(stroke
				(width 0.1)
				(type default)
			)
			(layer "F.Fab")
		)
		(fp_line
			(start 0.674878 1.100074)
			(end 0.674878 -1.100074)
			(stroke
				(width 0.1)
				(type default)
			)
			(layer "F.Fab")
		)
		(fp_poly
			(pts
				(xy -1.9431 -0.870204) (xy -1.50241 -0.649986) (xy -1.9431 -0.429768)
			)
			(stroke
				(width 0)
				(type default)
			)
			(fill yes)
			(layer "F.Fab")
		)
		(pad "1" smd rect
			(at -0.94996 -0.649986 270)
			(size 0.4318 0.6096)
			(layers "F.Cu" "F.Mask" "F.Paste")
			(net "OCP_V3_2_PRSNT0_R_N")
		)
		(pad "2" smd rect
			(at -0.94996 0 270)
			(size 0.4318 0.6096)
			(layers "F.Cu" "F.Mask" "F.Paste")
			(net "GND")
		)
		(pad "3" smd rect
			(at -0.94996 0.649986 270)
			(size 0.4318 0.6096)
			(layers "F.Cu" "F.Mask" "F.Paste")
			(net "OCP_V3_2_PRSNT1_R_N")
		)
		(pad "4" smd rect
			(at 0.94996 0.649986 270)
			(size 0.4318 0.6096)
			(layers "F.Cu" "F.Mask" "F.Paste")
			(net "HP_LVC3_OCP_V3_2_PRSNT2_N_R")
		)
		(pad "5" smd rect
			(at 0.94996 0 270)
			(size 0.4318 0.6096)
			(layers "F.Cu" "F.Mask" "F.Paste")
			(net "P3V3_AUX")
		)
		(pad "6" smd rect
			(at 0.94996 -0.649986 270)
			(size 0.4318 0.6096)
			(layers "F.Cu" "F.Mask" "F.Paste")
			(net "HP_LVC3_OCP_V3_2_PRSNT2_N_R")
		)
	)
	(footprint ""
		(layer "F.Cu")
		(at 20.190714 -110.875826 180)
		(property "Reference" "C2051"
			(at 0 0 180)
			(layer "F.SilkS")
			(hide yes)
			(effects
				(font
					(size 1.27 1.27)
				)
			)
		)
		(property "Value" ""
			(at 0 0 180)
			(layer "F.Fab")
			(effects
				(font
					(size 1.27 1.27)
				)
			)
		)
		(duplicate_pad_numbers_are_jumpers no)
		(fp_line
			(start 0.7874 0.4064)
			(end -0.7874 0.4064)
			(stroke
				(width 0.1524)
				(type default)
			)
			(layer "F.SilkS")
		)
		(fp_line
			(start 0.7874 -0.4064)
			(end 0.7874 0.4064)
			(stroke
				(width 0.1524)
				(type default)
			)
			(layer "F.SilkS")
		)
		(fp_line
			(start -0.7874 0.4064)
			(end -0.7874 -0.4064)
			(stroke
				(width 0.1524)
				(type default)
			)
			(layer "F.SilkS")
		)
		(fp_line
			(start -0.7874 -0.4064)
			(end 0.7874 -0.4064)
			(stroke
				(width 0.1524)
				(type default)
			)
			(layer "F.SilkS")
		)
		(fp_line
			(start 0.67945 0.3048)
			(end 0.120396 0.3048)
			(stroke
				(width 0.1)
				(type default)
			)
			(layer "F.Fab")
		)
		(fp_line
			(start 0.67945 -0.3048)
			(end 0.67945 0.3048)
			(stroke
				(width 0.1)
				(type default)
			)
			(layer "F.Fab")
		)
		(fp_line
			(start 0.12065 -0.2794)
			(end 0.12065 -0.3048)
			(stroke
				(width 0.1)
				(type default)
			)
			(layer "F.Fab")
		)
		(fp_line
			(start 0.12065 -0.3048)
			(end 0.67945 -0.3048)
			(stroke
				(width 0.1)
				(type default)
			)
			(layer "F.Fab")
		)
		(fp_line
			(start 0.120396 0.3048)
			(end 0.120396 0.2794)
			(stroke
				(width 0.1)
				(type default)
			)
			(layer "F.Fab")
		)
		(fp_line
			(start 0.120396 0.2794)
			(end -0.12065 0.2794)
			(stroke
				(width 0.1)
				(type default)
			)
			(layer "F.Fab")
		)
		(fp_line
			(start -0.12065 0.3048)
			(end -0.67945 0.3048)
			(stroke
				(width 0.1)
				(type default)
			)
			(layer "F.Fab")
		)
		(fp_line
			(start -0.12065 0.2794)
			(end -0.12065 0.3048)
			(stroke
				(width 0.1)
				(type default)
			)
			(layer "F.Fab")
		)
		(fp_line
			(start -0.12065 -0.2794)
			(end 0.12065 -0.2794)
			(stroke
				(width 0.1)
				(type default)
			)
			(layer "F.Fab")
		)
		(fp_line
			(start -0.12065 -0.305054)
			(end -0.12065 -0.2794)
			(stroke
				(width 0.1)
				(type default)
			)
			(layer "F.Fab")
		)
		(fp_line
			(start -0.67945 0.3048)
			(end -0.67945 -0.305054)
			(stroke
				(width 0.1)
				(type default)
			)
			(layer "F.Fab")
		)
		(fp_line
			(start -0.67945 -0.305054)
			(end -0.12065 -0.305054)
			(stroke
				(width 0.1)
				(type default)
			)
			(layer "F.Fab")
		)
		(pad "1" smd circle
			(at -0.40005 0 180)
			(size 0 0)
			(layers "F.Cu" "F.Mask" "F.Paste")
			(net "P3V3_ADC128_VCC")
		)
		(pad "2" smd circle
			(at 0.40005 0 180)
			(size 0 0)
			(layers "F.Cu" "F.Mask" "F.Paste")
			(net "GND")
		)
	)
	(footprint ""
		(layer "F.Cu")
		(at 53.278278 -408.517344 -90)
		(property "Reference" "C706"
			(at 0 0 270)
			(layer "F.SilkS")
			(hide yes)
			(effects
				(font
					(size 1.27 1.27)
				)
			)
		)
		(property "Value" ""
			(at 0 0 270)
			(layer "F.Fab")
			(effects
				(font
					(size 1.27 1.27)
				)
			)
		)
		(duplicate_pad_numbers_are_jumpers no)
		(fp_line
			(start -0.299974 0.150114)
			(end -0.299974 -0.150114)
			(stroke
				(width 0.1)
				(type default)
			)
			(layer "F.Fab")
		)
		(fp_line
			(start 0.299974 0.150114)
			(end -0.299974 0.150114)
			(stroke
				(width 0.1)
				(type default)
			)
			(layer "F.Fab")
		)
		(fp_line
			(start -0.299974 -0.150114)
			(end 0.299974 -0.150114)
			(stroke
				(width 0.1)
				(type default)
			)
			(layer "F.Fab")
		)
		(fp_line
			(start 0.299974 -0.150114)
			(end 0.299974 0.150114)
			(stroke
				(width 0.1)
				(type default)
			)
			(layer "F.Fab")
		)
		(pad "1" smd rect
			(at -0.2667 0 270)
			(size 0.3048 0.381)
			(layers "F.Cu" "F.Mask" "F.Paste")
			(net "P5E_CPU1_PE4_TX_C_DN<1>")
		)
		(pad "2" smd rect
			(at 0.2667 0 270)
			(size 0.3048 0.381)
			(layers "F.Cu" "F.Mask" "F.Paste")
			(net "P5E_CPU1_PE4_TX_DN<1>")
		)
	)
	(footprint ""
		(layer "F.Cu")
		(at 72.144382 -58.319924 180)
		(property "Reference" "PC2137"
			(at 0 0 180)
			(layer "F.SilkS")
			(hide yes)
			(effects
				(font
					(size 1.27 1.27)
				)
			)
		)
		(property "Value" ""
			(at 0 0 180)
			(layer "F.Fab")
			(effects
				(font
					(size 1.27 1.27)
				)
			)
		)
		(duplicate_pad_numbers_are_jumpers no)
		(fp_line
			(start 0.7874 0.4064)
			(end -0.7874 0.4064)
			(stroke
				(width 0.1524)
				(type default)
			)
			(layer "F.SilkS")
		)
		(fp_line
			(start 0.7874 -0.4064)
			(end 0.7874 0.4064)
			(stroke
				(width 0.1524)
				(type default)
			)
			(layer "F.SilkS")
		)
		(fp_line
			(start -0.7874 0.4064)
			(end -0.7874 -0.4064)
			(stroke
				(width 0.1524)
				(type default)
			)
			(layer "F.SilkS")
		)
		(fp_line
			(start -0.7874 -0.4064)
			(end 0.7874 -0.4064)
			(stroke
				(width 0.1524)
				(type default)
			)
			(layer "F.SilkS")
		)
		(fp_line
			(start 0.67945 0.3048)
			(end 0.120396 0.3048)
			(stroke
				(width 0.1)
				(type default)
			)
			(layer "F.Fab")
		)
		(fp_line
			(start 0.67945 -0.3048)
			(end 0.67945 0.3048)
			(stroke
				(width 0.1)
				(type default)
			)
			(layer "F.Fab")
		)
		(fp_line
			(start 0.12065 -0.2794)
			(end 0.12065 -0.3048)
			(stroke
				(width 0.1)
				(type default)
			)
			(layer "F.Fab")
		)
		(fp_line
			(start 0.12065 -0.3048)
			(end 0.67945 -0.3048)
			(stroke
				(width 0.1)
				(type default)
			)
			(layer "F.Fab")
		)
		(fp_line
			(start 0.120396 0.3048)
			(end 0.120396 0.2794)
			(stroke
				(width 0.1)
				(type default)
			)
			(layer "F.Fab")
		)
		(fp_line
			(start 0.120396 0.2794)
			(end -0.12065 0.2794)
			(stroke
				(width 0.1)
				(type default)
			)
			(layer "F.Fab")
		)
		(fp_line
			(start -0.12065 0.3048)
			(end -0.67945 0.3048)
			(stroke
				(width 0.1)
				(type default)
			)
			(layer "F.Fab")
		)
		(fp_line
			(start -0.12065 0.2794)
			(end -0.12065 0.3048)
			(stroke
				(width 0.1)
				(type default)
			)
			(layer "F.Fab")
		)
		(fp_line
			(start -0.12065 -0.2794)
			(end 0.12065 -0.2794)
			(stroke
				(width 0.1)
				(type default)
			)
			(layer "F.Fab")
		)
		(fp_line
			(start -0.12065 -0.305054)
			(end -0.12065 -0.2794)
			(stroke
				(width 0.1)
				(type default)
			)
			(layer "F.Fab")
		)
		(fp_line
			(start -0.67945 0.3048)
			(end -0.67945 -0.305054)
			(stroke
				(width 0.1)
				(type default)
			)
			(layer "F.Fab")
		)
		(fp_line
			(start -0.67945 -0.305054)
			(end -0.12065 -0.305054)
			(stroke
				(width 0.1)
				(type default)
			)
			(layer "F.Fab")
		)
		(pad "1" smd circle
			(at -0.40005 0 180)
			(size 0 0)
			(layers "F.Cu" "F.Mask" "F.Paste")
			(net "P3V3_OCP_V3_2_R")
		)
		(pad "2" smd circle
			(at 0.40005 0 180)
			(size 0 0)
			(layers "F.Cu" "F.Mask" "F.Paste")
			(net "GND")
		)
	)
	(footprint ""
		(layer "F.Cu")
		(at 20.485608 -385.066794 -90)
		(property "Reference" "R4662"
			(at 0 0 270)
			(layer "F.SilkS")
			(hide yes)
			(effects
				(font
					(size 1.27 1.27)
				)
			)
		)
		(property "Value" ""
			(at 0 0 270)
			(layer "F.Fab")
			(effects
				(font
					(size 1.27 1.27)
				)
			)
		)
		(duplicate_pad_numbers_are_jumpers no)
		(fp_line
			(start -0.7874 0.4064)
			(end -0.7874 -0.4064)
			(stroke
				(width 0.1524)
				(type default)
			)
			(layer "F.SilkS")
		)
		(fp_line
			(start 0.7874 0.4064)
			(end -0.020066 0.4064)
			(stroke
				(width 0.1524)
				(type default)
			)
			(layer "F.SilkS")
		)
		(fp_line
			(start -0.7874 -0.4064)
			(end 0.7874 -0.4064)
			(stroke
				(width 0.1524)
				(type default)
			)
			(layer "F.SilkS")
		)
		(fp_line
			(start -0.67945 0.3048)
			(end -0.67945 -0.305054)
			(stroke
				(width 0.1)
				(type default)
			)
			(layer "F.Fab")
		)
		(fp_line
			(start -0.12065 0.3048)
			(end -0.67945 0.3048)
			(stroke
				(width 0.1)
				(type default)
			)
			(layer "F.Fab")
		)
		(fp_line
			(start 0.120396 0.3048)
			(end 0.120396 0.2794)
			(stroke
				(width 0.1)
				(type default)
			)
			(layer "F.Fab")
		)
		(fp_line
			(start 0.67945 0.3048)
			(end 0.120396 0.3048)
			(stroke
				(width 0.1)
				(type default)
			)
			(layer "F.Fab")
		)
		(fp_line
			(start -0.12065 0.2794)
			(end -0.12065 0.3048)
			(stroke
				(width 0.1)
				(type default)
			)
			(layer "F.Fab")
		)
		(fp_line
			(start 0.120396 0.2794)
			(end -0.12065 0.2794)
			(stroke
				(width 0.1)
				(type default)
			)
			(layer "F.Fab")
		)
		(fp_line
			(start -0.12065 -0.2794)
			(end 0.12065 -0.2794)
			(stroke
				(width 0.1)
				(type default)
			)
			(layer "F.Fab")
		)
		(fp_line
			(start 0.12065 -0.2794)
			(end 0.12065 -0.3048)
			(stroke
				(width 0.1)
				(type default)
			)
			(layer "F.Fab")
		)
		(fp_line
			(start 0.12065 -0.3048)
			(end 0.67945 -0.3048)
			(stroke
				(width 0.1)
				(type default)
			)
			(layer "F.Fab")
		)
		(fp_line
			(start 0.67945 -0.3048)
			(end 0.67945 0.3048)
			(stroke
				(width 0.1)
				(type default)
			)
			(layer "F.Fab")
		)
		(fp_line
			(start -0.67945 -0.305054)
			(end -0.12065 -0.305054)
			(stroke
				(width 0.1)
				(type default)
			)
			(layer "F.Fab")
		)
		(fp_line
			(start -0.12065 -0.305054)
			(end -0.12065 -0.2794)
			(stroke
				(width 0.1)
				(type default)
			)
			(layer "F.Fab")
		)
		(pad "1" smd rect
			(at -0.40005 0 90)
			(size 0.4572 0.508)
			(layers "F.Cu" "F.Mask" "F.Paste")
			(net "P2E_MB_BMC_TX_C_DN<0>")
		)
		(pad "2" smd rect
			(at 0.40005 0 90)
			(size 0.4572 0.508)
			(layers "F.Cu" "F.Mask" "F.Paste")
			(net "P2E_MB_BMC_TX_C_R2_DN<0>")
		)
	)
)
